# TIMECARD (Time Appliance Project (Time Card)) — schematic netlist excerpt (pin names and nets, part order shuffled) for the footprints in the layout excerpt that follows; sources: Cadence DE-HDL packaged netlist, KiCad conversion of R4006-B0001-02_R01.brd

C317  CAPACITOR  18PF 5%  pkg SMC_0201R  page 23 : \1\ = SG ; \2\ = UNNAMED_12_CAPACITOR_I328_2
MAC_PIN2  NUT  pkg P_NUT_079C100  page 21 : \1\ = SG
TP47  TP_PIONT  pkg TP010CT020B030_PTH  page 25 : \1\ = FPGA_MGTRREF

(kicad_pcb
	(version 20260206)
	(generator "pcbnew")
	(generator_version "10.0")
	(general
		(thickness 1.6)
		(legacy_teardrops no)
	)
	(paper "A4")
	(title_block
		(title "timecard-production-celestica-r4006 — R4006-B0001-02_R01.brd")
		(comment 1 "Time Appliance Project (Time Card) / footprints 533-535 of 1113")
	)
	(layers
		(0 "F.Cu" signal "TOP")
		(4 "In1.Cu" signal "L02_GND1")
		(6 "In2.Cu" signal "L03_SIG1")
		(8 "In3.Cu" signal "L04_GND2")
		(10 "In4.Cu" signal "L05_VCC1")
		(12 "In5.Cu" signal "L06_VCC2")
		(14 "In6.Cu" signal "L07_GND3")
		(16 "In7.Cu" signal "L08_SIG2")
		(18 "In8.Cu" signal "L09_GND4")
		(2 "B.Cu" signal "BOTTOM")
		(9 "F.Adhes" user "F.Adhesive")
		(11 "B.Adhes" user "B.Adhesive")
		(13 "F.Paste" user "Package Geometry/Pastemask Top")
		(15 "B.Paste" user "Package Geometry/Pastemask Bottom")
		(5 "F.SilkS" user "Ref Des/Silkscreen Top")
		(7 "B.SilkS" user "Ref Des/Silkscreen Bottom")
		(1 "F.Mask" user "Board Geometry/Soldermask Top")
		(3 "B.Mask" user "Board Geometry/Soldermask Bottom")
		(17 "Dwgs.User" user "User.Drawings")
		(19 "Cmts.User" user "User.Comments")
		(21 "Eco1.User" user "User.Eco1")
		(23 "Eco2.User" user "User.Eco2")
		(25 "Edge.Cuts" user "Board Geometry/Outline")
		(27 "Margin" user)
		(31 "F.CrtYd" user "Package Geometry/Place Bound Top")
		(29 "B.CrtYd" user "Package Geometry/Place Bound Bottom")
		(35 "F.Fab" user "Ref Des/Assembly Top")
		(33 "B.Fab" user "Ref Des/Assembly Bottom")
	)
	(footprint ""
		(layer "F.Cu")
		(at 12.8778 -68.072)
		(property "Reference" "C317"
			(at 0.3302 -5.67563 0)
			(unlocked yes)
			(layer "F.SilkS")
			(effects
				(font
					(size 0.7874 0.5842)
					(thickness 0.1524)
				)
			)
		)
		(property "Value" "VAL*"
			(at 0.193548 2.13614 0)
			(unlocked yes)
			(layer "F.Fab")
			(hide yes)
			(effects
				(font
					(size 0.7874 0.5842)
					(thickness 0.1524)
				)
			)
		)
		(property "User Part Number" "PARTNUM*"
			(at 0.216154 4.185666 0)
			(unlocked yes)
			(layer "Cmts.User")
			(hide yes)
			(effects
				(font
					(size 0.7874 0.5842)
					(thickness 0.1524)
				)
			)
		)
		(property "Device Type" "CAPACITOR-G104-0A180-FJ,18PF,5%"
			(at 0.184404 1.180592 0)
			(unlocked yes)
			(layer "F.Fab")
			(hide yes)
			(effects
				(font
					(size 0.7874 0.5842)
					(thickness 0.1524)
				)
			)
		)
		(property "Tolerance" "TOL*"
			(at 0.216154 3.1496 0)
			(unlocked yes)
			(layer "Cmts.User")
			(hide yes)
			(effects
				(font
					(size 0.7874 0.5842)
					(thickness 0.1524)
				)
			)
		)
		(duplicate_pad_numbers_are_jumpers no)
		(fp_line
			(start -0.671322 -0.4445)
			(end 0.671322 -0.4445)
			(stroke
				(width 0.1)
				(type default)
			)
			(layer "F.SilkS")
		)
		(fp_line
			(start -0.671322 0.4445)
			(end -0.671322 -0.4445)
			(stroke
				(width 0.1)
				(type default)
			)
			(layer "F.SilkS")
		)
		(fp_line
			(start 0.671322 -0.4445)
			(end 0.671322 0.4445)
			(stroke
				(width 0.1)
				(type default)
			)
			(layer "F.SilkS")
		)
		(fp_line
			(start 0.671322 0.4445)
			(end -0.671322 0.4445)
			(stroke
				(width 0.1)
				(type default)
			)
			(layer "F.SilkS")
		)
		(fp_rect
			(start -0.671322 0.4445)
			(end 0.671322 -0.4445)
			(stroke
				(width 0)
				(type default)
			)
			(fill no)
			(layer "F.CrtYd")
		)
		(fp_line
			(start -0.31496 -0.1651)
			(end -0.31496 0.1651)
			(stroke
				(width 0.1)
				(type default)
			)
			(layer "F.Fab")
		)
		(fp_line
			(start -0.31496 0.1651)
			(end 0.31496 0.1651)
			(stroke
				(width 0.1)
				(type default)
			)
			(layer "F.Fab")
		)
		(fp_line
			(start 0.31496 -0.1651)
			(end -0.31496 -0.1651)
			(stroke
				(width 0.1)
				(type default)
			)
			(layer "F.Fab")
		)
		(fp_line
			(start 0.31496 0.1651)
			(end 0.31496 -0.1651)
			(stroke
				(width 0.1)
				(type default)
			)
			(layer "F.Fab")
		)
		(pad "1" smd rect
			(at -0.264922 0)
			(size 0.3048 0.381)
			(layers "F.Cu" "F.Mask" "F.Paste")
			(net "SG")
		)
		(pad "2" smd rect
			(at 0.264922 0)
			(size 0.3048 0.381)
			(layers "F.Cu" "F.Mask" "F.Paste")
			(net "UNNAMED_12_CAPACITOR_I328_2")
		)
		(zone
			(layer "F.Cu")
			(hatch none 0.5)
			(connect_pads
				(clearance 0)
			)
			(min_thickness 0.25)
			(keepout
				(tracks allowed)
				(vias not_allowed)
				(pads allowed)
				(copperpour not_allowed)
				(footprints allowed)
			)
			(placement
				(enabled no)
				(sheetname "")
			)
			(fill
				(thermal_gap 0.5)
				(thermal_bridge_width 0.5)
				(island_removal_mode 0)
			)
			(polygon
				(pts
					(xy 12.765278 -68.2625) (xy 12.765278 -67.8815) (xy 12.990322 -67.8815) (xy 12.990322 -68.2625)
				)
			)
		)
		(zone
			(layer "F.Cu")
			(hatch none 0.5)
			(connect_pads
				(clearance 0)
			)
			(min_thickness 0.25)
			(keepout
				(tracks not_allowed)
				(vias allowed)
				(pads allowed)
				(copperpour not_allowed)
				(footprints allowed)
			)
			(placement
				(enabled no)
				(sheetname "")
			)
			(fill
				(thermal_gap 0.5)
				(thermal_bridge_width 0.5)
				(island_removal_mode 0)
			)
			(polygon
				(pts
					(xy 12.765278 -67.8815) (xy 12.990322 -67.8815) (xy 12.990322 -68.2625) (xy 12.765278 -68.2625)
				)
			)
		)
	)
	(footprint ""
		(layer "F.Cu")
		(at 95.1484 -45.2628)
		(property "Reference" "TP47"
			(at -0.80645 1.27 90)
			(unlocked yes)
			(layer "F.SilkS")
			(effects
				(font
					(size 0.635 0.4064)
					(thickness 0.1524)
				)
				(justify left)
			)
		)
		(property "Value" ""
			(at 0 0 0)
			(layer "F.Fab")
			(effects
				(font
					(size 1.27 1.27)
				)
			)
		)
		(property "Device Type" "TP_PIONT-TP010CT020B030_PTH-TPA"
			(at -1.341882 0.996696 0)
			(unlocked yes)
			(layer "F.Fab")
			(hide yes)
			(effects
				(font
					(size 0.7874 0.5842)
					(thickness 0.000001)
				)
				(justify left)
			)
		)
		(duplicate_pad_numbers_are_jumpers no)
		(fp_poly
			(pts
				(arc
					(start 0.889 0)
					(mid -0.889 0)
					(end 0.889 0)
				)
			)
			(stroke
				(width 0)
				(type default)
			)
			(fill no)
			(layer "B.CrtYd")
		)
		(fp_poly
			(pts
				(arc
					(start 0.889 0)
					(mid -0.889 0)
					(end 0.889 0)
				)
			)
			(stroke
				(width 0)
				(type default)
			)
			(fill no)
			(layer "F.CrtYd")
		)
		(pad "1" thru_hole circle
			(at 0 0)
			(size 0.508 0.508)
			(drill 0.254)
			(layers "*.Cu" "*.Mask")
			(remove_unused_layers no)
			(net "FPGA_MGTRREF")
			(clearance 0.1016)
			(padstack
				(mode front_inner_back)
				(layer "Inner"
					(shape circle)
					(size 0.508 0.508)
					(clearance 0.1016)
				)
				(layer "B.Cu"
					(shape circle)
					(size 0.762 0.762)
					(clearance -0.0254)
				)
			)
		)
	)
	(footprint ""
		(layer "F.Cu")
		(at 32.021018 -46.746922)
		(property "Reference" "MAC_PIN2"
			(at 0.127762 2.580132 0)
			(unlocked yes)
			(layer "F.SilkS")
			(effects
				(font
					(size 0.7874 0.5842)
					(thickness 0.1524)
				)
			)
		)
		(property "Value" ""
			(at 0 0 0)
			(layer "F.Fab")
			(effects
				(font
					(size 1.27 1.27)
				)
			)
		)
		(property "User Part Number" "PARTNUM*"
			(at 0 3.826764 0)
			(unlocked yes)
			(layer "Cmts.User")
			(hide yes)
			(effects
				(font
					(size 0.7874 0.5842)
					(thickness 0.1524)
				)
			)
		)
		(property "Device Type" "NUT-A200-00029-FB"
			(at 0 2.632964 0)
			(unlocked yes)
			(layer "F.Fab")
			(hide yes)
			(effects
				(font
					(size 0.7874 0.5842)
					(thickness 0.1524)
				)
			)
		)
		(duplicate_pad_numbers_are_jumpers no)
		(fp_circle
			(center 0 0)
			(end 1.524 0)
			(stroke
				(width 0.1)
				(type default)
			)
			(fill no)
			(layer "F.SilkS")
		)
		(fp_poly
			(pts
				(arc
					(start -1.260856 -0.1524)
					(mid -0.898049 -0.898049)
					(end -0.1524 -1.260856)
				)
				(arc
					(start -0.1524 -0.991616)
					(mid -0.709411 -0.709411)
					(end -0.991616 -0.1524)
				)
			)
			(stroke
				(width 0)
				(type default)
			)
			(fill yes)
			(layer "F.Paste")
		)
		(fp_poly
			(pts
				(arc
					(start -0.1524 1.260856)
					(mid -0.898049 0.898049)
					(end -1.260856 0.1524)
				)
				(arc
					(start -0.991616 0.1524)
					(mid -0.709411 0.709411)
					(end -0.1524 0.991616)
				)
			)
			(stroke
				(width 0)
				(type default)
			)
			(fill yes)
			(layer "F.Paste")
		)
		(fp_poly
			(pts
				(arc
					(start 0.1524 -1.260856)
					(mid 0.898049 -0.898049)
					(end 1.260856 -0.1524)
				)
				(arc
					(start 0.991616 -0.1524)
					(mid 0.709411 -0.709411)
					(end 0.1524 -0.991616)
				)
			)
			(stroke
				(width 0)
				(type default)
			)
			(fill yes)
			(layer "F.Paste")
		)
		(fp_poly
			(pts
				(arc
					(start 1.260856 0.1524)
					(mid 0.898049 0.898049)
					(end 0.1524 1.260856)
				)
				(arc
					(start 0.1524 0.991616)
					(mid 0.709411 0.709411)
					(end 0.991616 0.1524)
				)
			)
			(stroke
				(width 0)
				(type default)
			)
			(fill yes)
			(layer "F.Paste")
		)
		(fp_poly
			(pts
				(arc
					(start 6.35 0)
					(mid -6.35 0)
					(end 6.35 0)
				)
			)
			(stroke
				(width 0)
				(type default)
			)
			(fill no)
			(layer "B.CrtYd")
		)
		(fp_poly
			(pts
				(arc
					(start 1.778 0)
					(mid -1.778 0)
					(end 1.778 0)
				)
			)
			(stroke
				(width 0)
				(type default)
			)
			(fill no)
			(layer "F.CrtYd")
		)
		(fp_circle
			(center 0 0)
			(end 1.1684 0)
			(stroke
				(width 0.1)
				(type default)
			)
			(fill no)
			(layer "F.Fab")
		)
		(pad "1" thru_hole circle
			(at 0 0)
			(size 2.54 2.54)
			(drill 2.0066)
			(layers "*.Cu" "*.Mask")
			(remove_unused_layers no)
			(net "SG")
			(thermal_gap 0.0254)
			(padstack
				(mode front_inner_back)
				(layer "Inner"
					(shape circle)
					(size 2.54 2.54)
					(clearance 0.0254)
				)
				(layer "B.Cu"
					(shape circle)
					(size 2.54 2.54)
				)
			)
		)
	)
)
